(kicad_pcb
	(version 20260206)
	(generator "pcbnew")
	(generator_version "10.0")
	(general
		(thickness 1.6)
		(legacy_teardrops no)
	)
	(paper "A4")
	(title_block
		(title "01162023_DA0F0TEBIF0_F0T_Expander_BD_F_brd_V02_OCP.brd")
		(comment 1 "Grand Teton / footprints 3950-3954 of 9728")
	)
	(layers
		(0 "F.Cu" signal "TOP")
		(4 "In1.Cu" signal "GND")
		(6 "In2.Cu" signal "VCC")
		(8 "In3.Cu" signal "VCC1")
		(10 "In4.Cu" signal "GND1")
		(12 "In5.Cu" signal "IN1")
		(14 "In6.Cu" signal "GND2")
		(16 "In7.Cu" signal "IN2")
		(18 "In8.Cu" signal "GND3")
		(20 "In9.Cu" signal "IN3")
		(22 "In10.Cu" signal "GND4")
		(24 "In11.Cu" signal "IN4")
		(26 "In12.Cu" signal "GND5")
		(28 "In13.Cu" signal "IN5")
		(30 "In14.Cu" signal "GND6")
		(32 "In15.Cu" signal "IN6")
		(34 "In16.Cu" signal "GND7")
		(2 "B.Cu" signal "BOTTOM")
		(9 "F.Adhes" user "F.Adhesive")
		(11 "B.Adhes" user "B.Adhesive")
		(13 "F.Paste" user "Package Geometry/Pastemask Top")
		(15 "B.Paste" user "Package Geometry/Pastemask Bottom")
		(5 "F.SilkS" user "Ref Des/Silkscreen Top")
		(7 "B.SilkS" user "Ref Des/Silkscreen Bottom")
		(1 "F.Mask" user "Board Geometry/Soldermask Top")
		(3 "B.Mask" user "Board Geometry/Soldermask Bottom")
		(17 "Dwgs.User" user "User.Drawings")
		(19 "Cmts.User" user "User.Comments")
		(21 "Eco1.User" user "User.Eco1")
		(23 "Eco2.User" user "User.Eco2")
		(25 "Edge.Cuts" user "Board Geometry/Outline")
		(27 "Margin" user)
		(31 "F.CrtYd" user "Package Geometry/Place Bound Top")
		(29 "B.CrtYd" user "Package Geometry/Place Bound Bottom")
		(35 "F.Fab" user "Ref Des/Assembly Top")
		(33 "B.Fab" user "Ref Des/Assembly Bottom")
	)
	(footprint ""
		(layer "F.Cu")
		(at 255.045972 -46.4439 180)
		(property "Reference" "U71"
			(at -0.122428 -2.45237 0)
			(unlocked yes)
			(layer "F.SilkS")
			(effects
				(font
					(size 0.7874 0.5842)
					(thickness 0.1524)
				)
			)
		)
		(property "Value" ""
			(at 0 0 180)
			(layer "F.Fab")
			(effects
				(font
					(size 1.27 1.27)
				)
			)
		)
		(duplicate_pad_numbers_are_jumpers no)
		(fp_line
			(start 1.500124 1.500124)
			(end 1.004062 1.500124)
			(stroke
				(width 0.1524)
				(type default)
			)
			(layer "F.SilkS")
		)
		(fp_line
			(start 1.500124 1.004062)
			(end 1.500124 1.500124)
			(stroke
				(width 0.1524)
				(type default)
			)
			(layer "F.SilkS")
		)
		(fp_line
			(start 1.500124 -1.500124)
			(end 1.500124 -1.004062)
			(stroke
				(width 0.1524)
				(type default)
			)
			(layer "F.SilkS")
		)
		(fp_line
			(start 1.004062 -1.500124)
			(end 1.500124 -1.500124)
			(stroke
				(width 0.1524)
				(type default)
			)
			(layer "F.SilkS")
		)
		(fp_line
			(start -1.004062 1.500124)
			(end -1.500124 1.500124)
			(stroke
				(width 0.1524)
				(type default)
			)
			(layer "F.SilkS")
		)
		(fp_line
			(start -1.500124 1.500124)
			(end -1.500124 1.004062)
			(stroke
				(width 0.1524)
				(type default)
			)
			(layer "F.SilkS")
		)
		(fp_line
			(start -1.500124 -1.004062)
			(end -1.500124 -1.500124)
			(stroke
				(width 0.1524)
				(type default)
			)
			(layer "F.SilkS")
		)
		(fp_line
			(start -1.500124 -1.500124)
			(end -1.004062 -1.500124)
			(stroke
				(width 0.1524)
				(type default)
			)
			(layer "F.SilkS")
		)
		(fp_poly
			(pts
				(xy -1.97104 -2.39649) (xy -2.689352 -1.677924) (xy -1.61163 -1.318768)
			)
			(stroke
				(width 0)
				(type default)
			)
			(fill yes)
			(layer "F.SilkS")
		)
		(fp_line
			(start 1.500124 1.500124)
			(end -1.500124 1.500124)
			(stroke
				(width 0.1)
				(type default)
			)
			(layer "F.Fab")
		)
		(fp_line
			(start 1.500124 -1.500124)
			(end 1.500124 1.500124)
			(stroke
				(width 0.1)
				(type default)
			)
			(layer "F.Fab")
		)
		(fp_line
			(start -1.500124 1.500124)
			(end -1.500124 -1.500124)
			(stroke
				(width 0.1)
				(type default)
			)
			(layer "F.Fab")
		)
		(fp_line
			(start -1.500124 -1.500124)
			(end 1.500124 -1.500124)
			(stroke
				(width 0.1)
				(type default)
			)
			(layer "F.Fab")
		)
		(fp_poly
			(pts
				(xy -2.847848 -1.258062) (xy -2.847848 -0.242062) (xy -1.831848 -0.750062)
			)
			(stroke
				(width 0)
				(type default)
			)
			(fill yes)
			(layer "F.Fab")
		)
		(pad "1" smd rect
			(at -1.400048 -0.750062 90)
			(size 0.2286 0.6096)
			(layers "F.Cu" "F.Mask" "F.Paste")
			(net "SSD8_ADC_A1")
		)
		(pad "2" smd rect
			(at -1.400048 -0.249936 90)
			(size 0.2286 0.6096)
			(layers "F.Cu" "F.Mask" "F.Paste")
			(net "SSD8_ADC_A0")
		)
		(pad "3" smd rect
			(at -1.400048 0.249936 90)
			(size 0.2286 0.6096)
			(layers "F.Cu" "F.Mask" "F.Paste")
			(net "SSD8_ADC_ALERT_N")
		)
		(pad "4" smd rect
			(at -1.400048 0.750062 90)
			(size 0.2286 0.6096)
			(layers "F.Cu" "F.Mask" "F.Paste")
			(net "SMB_SSD8_ADC_SDA")
		)
		(pad "5" smd rect
			(at -0.750062 1.400048 180)
			(size 0.2286 0.6096)
			(layers "F.Cu" "F.Mask" "F.Paste")
			(net "SMB_SSD8_ADC_SCL")
		)
		(pad "6" smd rect
			(at -0.249936 1.400048 180)
			(size 0.2286 0.6096)
			(layers "F.Cu" "F.Mask" "F.Paste")
			(net "Net_8714")
		)
		(pad "7" smd rect
			(at 0.249936 1.400048 180)
			(size 0.2286 0.6096)
			(layers "F.Cu" "F.Mask" "F.Paste")
			(net "Net_8713")
		)
		(pad "8" smd rect
			(at 0.750062 1.400048 180)
			(size 0.2286 0.6096)
			(layers "F.Cu" "F.Mask" "F.Paste")
			(net "Net_8712")
		)
		(pad "9" smd rect
			(at 1.400048 0.750062 90)
			(size 0.2286 0.6096)
			(layers "F.Cu" "F.Mask" "F.Paste")
			(net "P3V3_AUX")
		)
		(pad "10" smd rect
			(at 1.400048 0.249936 90)
			(size 0.2286 0.6096)
			(layers "F.Cu" "F.Mask" "F.Paste")
			(net "GND")
		)
		(pad "11" smd rect
			(at 1.400048 -0.249936 90)
			(size 0.2286 0.6096)
			(layers "F.Cu" "F.Mask" "F.Paste")
			(net "P12V_SSD8_R")
		)
		(pad "12" smd rect
			(at 1.400048 -0.750062 90)
			(size 0.2286 0.6096)
			(layers "F.Cu" "F.Mask" "F.Paste")
			(net "P12V_SSD8_VIN_N")
		)
		(pad "13" smd rect
			(at 0.750062 -1.400048 180)
			(size 0.2286 0.6096)
			(layers "F.Cu" "F.Mask" "F.Paste")
			(net "P12V_SSD8_VIN_P")
		)
		(pad "14" smd rect
			(at 0.249936 -1.400048 180)
			(size 0.2286 0.6096)
			(layers "F.Cu" "F.Mask" "F.Paste")
			(net "Net_8711")
		)
		(pad "15" smd rect
			(at -0.249936 -1.400048 180)
			(size 0.2286 0.6096)
			(layers "F.Cu" "F.Mask" "F.Paste")
			(net "Net_8710")
		)
		(pad "16" smd rect
			(at -0.750062 -1.400048 180)
			(size 0.2286 0.6096)
			(layers "F.Cu" "F.Mask" "F.Paste")
			(net "Net_8709")
		)
		(pad "TH" smd rect
			(at 0 0 180)
			(size 1.7018 1.7018)
			(layers "F.Cu" "F.Mask" "F.Paste")
			(net "GND")
		)
		(zone
			(layer "F.Cu")
			(hatch none 0.5)
			(connect_pads
				(clearance 0)
			)
			(min_thickness 0.25)
			(keepout
				(tracks not_allowed)
				(vias allowed)
				(pads allowed)
				(copperpour not_allowed)
				(footprints allowed)
			)
			(placement
				(enabled no)
				(sheetname "")
			)
			(fill
				(thermal_gap 0.5)
				(thermal_bridge_width 0.5)
				(island_removal_mode 0)
			)
			(polygon
				(pts
					(xy 256.09042 -46.4185) (xy 256.09042 -45.399452) (xy 254.001524 -45.399452) (xy 254.001524 -47.488348)
					(xy 256.09042 -47.488348) (xy 256.09042 -46.4439) (xy 255.947672 -46.4439) (xy 255.947672 -47.3456)
					(xy 254.144272 -47.3456) (xy 254.144272 -45.5422) (xy 255.947672 -45.5422) (xy 255.947672 -46.4185)
				)
			)
		)
	)
	(footprint ""
		(layer "F.Cu")
		(at 219.623894 -174.99838)
		(property "Reference" "U360"
			(at -0.929894 2.38125 0)
			(unlocked yes)
			(layer "F.SilkS")
			(effects
				(font
					(size 0.7874 0.5842)
					(thickness 0.1524)
				)
				(justify left)
			)
		)
		(property "Value" ""
			(at 0 0 0)
			(layer "F.Fab")
			(effects
				(font
					(size 1.27 1.27)
				)
			)
		)
		(duplicate_pad_numbers_are_jumpers no)
		(fp_line
			(start -2.0574 -1.651)
			(end -0.381 -1.651)
			(stroke
				(width 0.1524)
				(type default)
			)
			(layer "F.SilkS")
		)
		(fp_line
			(start -2.0574 1.651)
			(end -2.0574 -1.651)
			(stroke
				(width 0.1524)
				(type default)
			)
			(layer "F.SilkS")
		)
		(fp_line
			(start -0.381 -1.651)
			(end 0 -1.016)
			(stroke
				(width 0.1524)
				(type default)
			)
			(layer "F.SilkS")
		)
		(fp_line
			(start 0 -1.016)
			(end 0.381 -1.651)
			(stroke
				(width 0.1524)
				(type default)
			)
			(layer "F.SilkS")
		)
		(fp_line
			(start 0.381 -1.651)
			(end 2.0574 -1.651)
			(stroke
				(width 0.1524)
				(type default)
			)
			(layer "F.SilkS")
		)
		(fp_line
			(start 2.0574 -1.651)
			(end 2.0574 1.651)
			(stroke
				(width 0.1524)
				(type default)
			)
			(layer "F.SilkS")
		)
		(fp_line
			(start 2.0574 1.651)
			(end -2.0574 1.651)
			(stroke
				(width 0.1524)
				(type default)
			)
			(layer "F.SilkS")
		)
		(fp_poly
			(pts
				(xy -3.102864 -0.719328) (xy -3.102864 -1.344168) (xy -2.549144 -1.016)
			)
			(stroke
				(width 0)
				(type default)
			)
			(fill yes)
			(layer "F.SilkS")
		)
		(fp_line
			(start -1.599946 -1.199896)
			(end -0.899922 -1.199896)
			(stroke
				(width 0.1)
				(type default)
			)
			(layer "F.Fab")
		)
		(fp_line
			(start -1.599946 1.199896)
			(end -1.599946 -1.199896)
			(stroke
				(width 0.1)
				(type default)
			)
			(layer "F.Fab")
		)
		(fp_line
			(start -0.899922 -1.549908)
			(end 0.899922 -1.549908)
			(stroke
				(width 0.1)
				(type default)
			)
			(layer "F.Fab")
		)
		(fp_line
			(start -0.899922 -1.199896)
			(end -0.899922 -1.549908)
			(stroke
				(width 0.1)
				(type default)
			)
			(layer "F.Fab")
		)
		(fp_line
			(start -0.899922 1.199896)
			(end -1.599946 1.199896)
			(stroke
				(width 0.1)
				(type default)
			)
			(layer "F.Fab")
		)
		(fp_line
			(start -0.899922 1.549908)
			(end -0.899922 1.199896)
			(stroke
				(width 0.1)
				(type default)
			)
			(layer "F.Fab")
		)
		(fp_line
			(start 0.899922 -1.549908)
			(end 0.899922 -1.199896)
			(stroke
				(width 0.1)
				(type default)
			)
			(layer "F.Fab")
		)
		(fp_line
			(start 0.899922 -1.199896)
			(end 1.599946 -1.199896)
			(stroke
				(width 0.1)
				(type default)
			)
			(layer "F.Fab")
		)
		(fp_line
			(start 0.899922 1.199896)
			(end 0.899922 1.549908)
			(stroke
				(width 0.1)
				(type default)
			)
			(layer "F.Fab")
		)
		(fp_line
			(start 0.899922 1.549908)
			(end -0.899922 1.549908)
			(stroke
				(width 0.1)
				(type default)
			)
			(layer "F.Fab")
		)
		(fp_line
			(start 1.599946 -1.199896)
			(end 1.599946 1.199896)
			(stroke
				(width 0.1)
				(type default)
			)
			(layer "F.Fab")
		)
		(fp_line
			(start 1.599946 1.199896)
			(end 0.899922 1.199896)
			(stroke
				(width 0.1)
				(type default)
			)
			(layer "F.Fab")
		)
		(fp_poly
			(pts
				(xy -2.71272 -0.719328) (xy -2.71272 -1.344168) (xy -2.159 -1.016)
			)
			(stroke
				(width 0)
				(type default)
			)
			(fill yes)
			(layer "F.Fab")
		)
		(pad "1" smd rect
			(at -1.225042 -0.94996 270)
			(size 0.5588 1.3462)
			(layers "F.Cu" "F.Mask" "F.Paste")
			(net "RST_MB_BIC_ISO_R_N")
		)
		(pad "2" smd rect
			(at -1.225042 0 270)
			(size 0.5588 1.3462)
			(layers "F.Cu" "F.Mask" "F.Paste")
			(net "RST_BIC_SELF_HW_RST_R_N")
		)
		(pad "3" smd rect
			(at -1.225042 0.94996 270)
			(size 0.5588 1.3462)
			(layers "F.Cu" "F.Mask" "F.Paste")
			(net "GND")
		)
		(pad "4" smd rect
			(at 1.225042 0.94996 270)
			(size 0.5588 1.3462)
			(layers "F.Cu" "F.Mask" "F.Paste")
			(net "RST_FW_BIC_PLTRST_N")
		)
		(pad "5" smd rect
			(at 1.225042 -0.94996 270)
			(size 0.5588 1.3462)
			(layers "F.Cu" "F.Mask" "F.Paste")
			(net "P3V3_AUX")
		)
	)
	(footprint ""
		(layer "F.Cu")
		(at 236.887512 -234.728004 -90)
		(property "Reference" "R6188"
			(at 0 0 270)
			(layer "F.SilkS")
			(hide yes)
			(effects
				(font
					(size 1.27 1.27)
				)
			)
		)
		(property "Value" ""
			(at 0 0 270)
			(layer "F.Fab")
			(effects
				(font
					(size 1.27 1.27)
				)
			)
		)
		(duplicate_pad_numbers_are_jumpers no)
		(fp_line
			(start -0.7874 0.4064)
			(end -0.7874 -0.4064)
			(stroke
				(width 0.1524)
				(type default)
			)
			(layer "F.SilkS")
		)
		(fp_line
			(start 0.7874 0.4064)
			(end -0.7874 0.4064)
			(stroke
				(width 0.1524)
				(type default)
			)
			(layer "F.SilkS")
		)
		(fp_line
			(start -0.7874 -0.4064)
			(end 0.7874 -0.4064)
			(stroke
				(width 0.1524)
				(type default)
			)
			(layer "F.SilkS")
		)
		(fp_line
			(start 0.7874 -0.4064)
			(end 0.7874 0.4064)
			(stroke
				(width 0.1524)
				(type default)
			)
			(layer "F.SilkS")
		)
		(fp_line
			(start -0.67945 0.3048)
			(end -0.67945 -0.305054)
			(stroke
				(width 0.1)
				(type default)
			)
			(layer "F.Fab")
		)
		(fp_line
			(start -0.12065 0.3048)
			(end -0.67945 0.3048)
			(stroke
				(width 0.1)
				(type default)
			)
			(layer "F.Fab")
		)
		(fp_line
			(start 0.120396 0.3048)
			(end 0.120396 0.2794)
			(stroke
				(width 0.1)
				(type default)
			)
			(layer "F.Fab")
		)
		(fp_line
			(start 0.67945 0.3048)
			(end 0.120396 0.3048)
			(stroke
				(width 0.1)
				(type default)
			)
			(layer "F.Fab")
		)
		(fp_line
			(start -0.12065 0.2794)
			(end -0.12065 0.3048)
			(stroke
				(width 0.1)
				(type default)
			)
			(layer "F.Fab")
		)
		(fp_line
			(start 0.120396 0.2794)
			(end -0.12065 0.2794)
			(stroke
				(width 0.1)
				(type default)
			)
			(layer "F.Fab")
		)
		(fp_line
			(start -0.12065 -0.2794)
			(end 0.12065 -0.2794)
			(stroke
				(width 0.1)
				(type default)
			)
			(layer "F.Fab")
		)
		(fp_line
			(start 0.12065 -0.2794)
			(end 0.12065 -0.3048)
			(stroke
				(width 0.1)
				(type default)
			)
			(layer "F.Fab")
		)
		(fp_line
			(start 0.12065 -0.3048)
			(end 0.67945 -0.3048)
			(stroke
				(width 0.1)
				(type default)
			)
			(layer "F.Fab")
		)
		(fp_line
			(start 0.67945 -0.3048)
			(end 0.67945 0.3048)
			(stroke
				(width 0.1)
				(type default)
			)
			(layer "F.Fab")
		)
		(fp_line
			(start -0.67945 -0.305054)
			(end -0.12065 -0.305054)
			(stroke
				(width 0.1)
				(type default)
			)
			(layer "F.Fab")
		)
		(fp_line
			(start -0.12065 -0.305054)
			(end -0.12065 -0.2794)
			(stroke
				(width 0.1)
				(type default)
			)
			(layer "F.Fab")
		)
		(pad "1" smd circle
			(at -0.40005 0 270)
			(size 0 0)
			(layers "F.Cu" "F.Mask" "F.Paste")
			(net "GND")
		)
		(pad "2" smd circle
			(at 0.40005 0 270)
			(size 0 0)
			(layers "F.Cu" "F.Mask" "F.Paste")
			(net "SSD6_PWRDIS_BIC_R")
		)
	)
	(footprint ""
		(layer "F.Cu")
		(at 265.487658 -301.220632)
		(property "Reference" "C3372"
			(at 0 0 0)
			(layer "F.SilkS")
			(hide yes)
			(effects
				(font
					(size 1.27 1.27)
				)
			)
		)
		(property "Value" ""
			(at 0 0 0)
			(layer "F.Fab")
			(effects
				(font
					(size 1.27 1.27)
				)
			)
		)
		(duplicate_pad_numbers_are_jumpers no)
		(fp_line
			(start -1.2954 -0.5842)
			(end 1.2954 -0.5842)
			(stroke
				(width 0.1524)
				(type default)
			)
			(layer "F.SilkS")
		)
		(fp_line
			(start -1.2954 0.5842)
			(end -1.2954 -0.5842)
			(stroke
				(width 0.1524)
				(type default)
			)
			(layer "F.SilkS")
		)
		(fp_line
			(start 1.2954 -0.5842)
			(end 1.2954 0.5842)
			(stroke
				(width 0.1524)
				(type default)
			)
			(layer "F.SilkS")
		)
		(fp_line
			(start 1.2954 0.5842)
			(end -1.2954 0.5842)
			(stroke
				(width 0.1524)
				(type default)
			)
			(layer "F.SilkS")
		)
		(fp_line
			(start -1.1938 -0.4064)
			(end -0.8636 -0.4064)
			(stroke
				(width 0.1)
				(type default)
			)
			(layer "F.Fab")
		)
		(fp_line
			(start -1.1938 0.4064)
			(end -1.1938 -0.4064)
			(stroke
				(width 0.1)
				(type default)
			)
			(layer "F.Fab")
		)
		(fp_line
			(start -0.8636 -0.4572)
			(end 0.8636 -0.4572)
			(stroke
				(width 0.1)
				(type default)
			)
			(layer "F.Fab")
		)
		(fp_line
			(start -0.8636 -0.4064)
			(end -0.8636 -0.4572)
			(stroke
				(width 0.1)
				(type default)
			)
			(layer "F.Fab")
		)
		(fp_line
			(start -0.8636 0.4064)
			(end -1.1938 0.4064)
			(stroke
				(width 0.1)
				(type default)
			)
			(layer "F.Fab")
		)
		(fp_line
			(start -0.8636 0.4572)
			(end -0.8636 0.4064)
			(stroke
				(width 0.1)
				(type default)
			)
			(layer "F.Fab")
		)
		(fp_line
			(start 0.8636 -0.4572)
			(end 0.8636 -0.4064)
			(stroke
				(width 0.1)
				(type default)
			)
			(layer "F.Fab")
		)
		(fp_line
			(start 0.8636 -0.4064)
			(end 1.1938 -0.4064)
			(stroke
				(width 0.1)
				(type default)
			)
			(layer "F.Fab")
		)
		(fp_line
			(start 0.8636 0.4064)
			(end 0.8636 0.4572)
			(stroke
				(width 0.1)
				(type default)
			)
			(layer "F.Fab")
		)
		(fp_line
			(start 0.8636 0.4572)
			(end -0.8636 0.4572)
			(stroke
				(width 0.1)
				(type default)
			)
			(layer "F.Fab")
		)
		(fp_line
			(start 1.1938 -0.4064)
			(end 1.1938 0.4064)
			(stroke
				(width 0.1)
				(type default)
			)
			(layer "F.Fab")
		)
		(fp_line
			(start 1.1938 0.4064)
			(end 0.8636 0.4064)
			(stroke
				(width 0.1)
				(type default)
			)
			(layer "F.Fab")
		)
		(pad "1" smd rect
			(at -0.7366 0 270)
			(size 0.7112 0.8128)
			(layers "F.Cu" "F.Mask" "F.Paste")
			(net "PCEPLL1_VDDA18_PEX2")
		)
		(pad "2" smd rect
			(at 0.7366 0 270)
			(size 0.7112 0.8128)
			(layers "F.Cu" "F.Mask" "F.Paste")
			(net "GND")
		)
	)
	(footprint ""
		(layer "F.Cu")
		(at 7.668768 -156.288994 -90)
		(property "Reference" "PR6866"
			(at 0 0 270)
			(layer "F.SilkS")
			(hide yes)
			(effects
				(font
					(size 1.27 1.27)
				)
			)
		)
		(property "Value" ""
			(at 0 0 270)
			(layer "F.Fab")
			(effects
				(font
					(size 1.27 1.27)
				)
			)
		)
		(duplicate_pad_numbers_are_jumpers no)
		(fp_line
			(start -0.7874 0.4064)
			(end -0.7874 -0.4064)
			(stroke
				(width 0.1524)
				(type default)
			)
			(layer "F.SilkS")
		)
		(fp_line
			(start 0.7874 0.4064)
			(end -0.7874 0.4064)
			(stroke
				(width 0.1524)
				(type default)
			)
			(layer "F.SilkS")
		)
		(fp_line
			(start -0.7874 -0.4064)
			(end 0.7874 -0.4064)
			(stroke
				(width 0.1524)
				(type default)
			)
			(layer "F.SilkS")
		)
		(fp_line
			(start 0.7874 -0.4064)
			(end 0.7874 0.4064)
			(stroke
				(width 0.1524)
				(type default)
			)
			(layer "F.SilkS")
		)
		(fp_line
			(start -0.67945 0.3048)
			(end -0.67945 -0.305054)
			(stroke
				(width 0.1)
				(type default)
			)
			(layer "F.Fab")
		)
		(fp_line
			(start -0.12065 0.3048)
			(end -0.67945 0.3048)
			(stroke
				(width 0.1)
				(type default)
			)
			(layer "F.Fab")
		)
		(fp_line
			(start 0.120396 0.3048)
			(end 0.120396 0.2794)
			(stroke
				(width 0.1)
				(type default)
			)
			(layer "F.Fab")
		)
		(fp_line
			(start 0.67945 0.3048)
			(end 0.120396 0.3048)
			(stroke
				(width 0.1)
				(type default)
			)
			(layer "F.Fab")
		)
		(fp_line
			(start -0.12065 0.2794)
			(end -0.12065 0.3048)
			(stroke
				(width 0.1)
				(type default)
			)
			(layer "F.Fab")
		)
		(fp_line
			(start 0.120396 0.2794)
			(end -0.12065 0.2794)
			(stroke
				(width 0.1)
				(type default)
			)
			(layer "F.Fab")
		)
		(fp_line
			(start -0.12065 -0.2794)
			(end 0.12065 -0.2794)
			(stroke
				(width 0.1)
				(type default)
			)
			(layer "F.Fab")
		)
		(fp_line
			(start 0.12065 -0.2794)
			(end 0.12065 -0.3048)
			(stroke
				(width 0.1)
				(type default)
			)
			(layer "F.Fab")
		)
		(fp_line
			(start 0.12065 -0.3048)
			(end 0.67945 -0.3048)
			(stroke
				(width 0.1)
				(type default)
			)
			(layer "F.Fab")
		)
		(fp_line
			(start 0.67945 -0.3048)
			(end 0.67945 0.3048)
			(stroke
				(width 0.1)
				(type default)
			)
			(layer "F.Fab")
		)
		(fp_line
			(start -0.67945 -0.305054)
			(end -0.12065 -0.305054)
			(stroke
				(width 0.1)
				(type default)
			)
			(layer "F.Fab")
		)
		(fp_line
			(start -0.12065 -0.305054)
			(end -0.12065 -0.2794)
			(stroke
				(width 0.1)
				(type default)
			)
			(layer "F.Fab")
		)
		(pad "1" smd circle
			(at -0.40005 0 270)
			(size 0 0)
			(layers "F.Cu" "F.Mask" "F.Paste")
			(net "P12V_NIC0_CO_OV_FB")
		)
		(pad "2" smd circle
			(at 0.40005 0 270)
			(size 0 0)
			(layers "F.Cu" "F.Mask" "F.Paste")
			(net "P12V_AUX")
		)
	)
)
